# SCM (Grand Teton) — schematic netlist excerpt (pin names and nets, part order shuffled) for the footprints in the layout excerpt that follows; sources: Cadence DE-HDL packaged netlist, KiCad conversion of 12092022_DA0F0TMDCD0_F0T_Management_Board_D_brd_V3_OCP.brd

R393  Q_RES  0 5% CHIP  pkg 0402LF  page 54 : A = EN_P1V8 ; B = EN_P1V8_R
PR242  Q_RES  10K 1% CHIP  pkg 0402LF  page 52 : A = P3V3_AUX ; B = PWRGD_P3V3_AUX_R

(kicad_pcb
	(version 20260206)
	(generator "pcbnew")
	(generator_version "10.0")
	(general
		(thickness 1.6)
		(legacy_teardrops no)
	)
	(paper "A4")
	(title_block
		(title "12092022_DA0F0TMDCD0_F0T_Management_Board_D_brd_V3_OCP.brd")
		(comment 1 "Grand Teton / footprints 667-668 of 1440")
	)
	(layers
		(0 "F.Cu" signal "TOP")
		(4 "In1.Cu" signal "GND")
		(6 "In2.Cu" signal "IN1")
		(8 "In3.Cu" signal "GND1")
		(10 "In4.Cu" signal "IN2")
		(12 "In5.Cu" signal "VCC")
		(14 "In6.Cu" signal "VCC1")
		(16 "In7.Cu" signal "IN3")
		(18 "In8.Cu" signal "GND2")
		(20 "In9.Cu" signal "IN4")
		(22 "In10.Cu" signal "GND3")
		(2 "B.Cu" signal "BOTTOM")
		(9 "F.Adhes" user "F.Adhesive")
		(11 "B.Adhes" user "B.Adhesive")
		(13 "F.Paste" user "Package Geometry/Pastemask Top")
		(15 "B.Paste" user "Package Geometry/Pastemask Bottom")
		(5 "F.SilkS" user "Ref Des/Silkscreen Top")
		(7 "B.SilkS" user "Ref Des/Silkscreen Bottom")
		(1 "F.Mask" user "Board Geometry/Soldermask Top")
		(3 "B.Mask" user "Board Geometry/Soldermask Bottom")
		(17 "Dwgs.User" user "User.Drawings")
		(19 "Cmts.User" user "User.Comments")
		(21 "Eco1.User" user "User.Eco1")
		(23 "Eco2.User" user "User.Eco2")
		(25 "Edge.Cuts" user "Board Geometry/Outline")
		(27 "Margin" user)
		(31 "F.CrtYd" user "Package Geometry/Place Bound Top")
		(29 "B.CrtYd" user "Package Geometry/Place Bound Bottom")
		(35 "F.Fab" user "Ref Des/Assembly Top")
		(33 "B.Fab" user "Ref Des/Assembly Bottom")
	)
	(footprint ""
		(layer "F.Cu")
		(at 33.629092 -57.452768 -90)
		(property "Reference" "R393"
			(at 0 0 270)
			(layer "F.SilkS")
			(hide yes)
			(effects
				(font
					(size 1.27 1.27)
				)
			)
		)
		(property "Value" ""
			(at 0 0 270)
			(layer "F.Fab")
			(effects
				(font
					(size 1.27 1.27)
				)
			)
		)
		(duplicate_pad_numbers_are_jumpers no)
		(fp_line
			(start -0.7874 0.4064)
			(end -0.7874 -0.4064)
			(stroke
				(width 0.1524)
				(type default)
			)
			(layer "F.SilkS")
		)
		(fp_line
			(start 0.7874 0.4064)
			(end -0.7874 0.4064)
			(stroke
				(width 0.1524)
				(type default)
			)
			(layer "F.SilkS")
		)
		(fp_line
			(start -0.7874 -0.4064)
			(end 0.7874 -0.4064)
			(stroke
				(width 0.1524)
				(type default)
			)
			(layer "F.SilkS")
		)
		(fp_line
			(start 0.7874 -0.4064)
			(end 0.7874 0.4064)
			(stroke
				(width 0.1524)
				(type default)
			)
			(layer "F.SilkS")
		)
		(fp_line
			(start -0.67945 0.3048)
			(end -0.67945 -0.305054)
			(stroke
				(width 0.1)
				(type default)
			)
			(layer "F.Fab")
		)
		(fp_line
			(start -0.12065 0.3048)
			(end -0.67945 0.3048)
			(stroke
				(width 0.1)
				(type default)
			)
			(layer "F.Fab")
		)
		(fp_line
			(start 0.120396 0.3048)
			(end 0.120396 0.2794)
			(stroke
				(width 0.1)
				(type default)
			)
			(layer "F.Fab")
		)
		(fp_line
			(start 0.67945 0.3048)
			(end 0.120396 0.3048)
			(stroke
				(width 0.1)
				(type default)
			)
			(layer "F.Fab")
		)
		(fp_line
			(start -0.12065 0.2794)
			(end -0.12065 0.3048)
			(stroke
				(width 0.1)
				(type default)
			)
			(layer "F.Fab")
		)
		(fp_line
			(start 0.120396 0.2794)
			(end -0.12065 0.2794)
			(stroke
				(width 0.1)
				(type default)
			)
			(layer "F.Fab")
		)
		(fp_line
			(start -0.12065 -0.2794)
			(end 0.12065 -0.2794)
			(stroke
				(width 0.1)
				(type default)
			)
			(layer "F.Fab")
		)
		(fp_line
			(start 0.12065 -0.2794)
			(end 0.12065 -0.3048)
			(stroke
				(width 0.1)
				(type default)
			)
			(layer "F.Fab")
		)
		(fp_line
			(start 0.12065 -0.3048)
			(end 0.67945 -0.3048)
			(stroke
				(width 0.1)
				(type default)
			)
			(layer "F.Fab")
		)
		(fp_line
			(start 0.67945 -0.3048)
			(end 0.67945 0.3048)
			(stroke
				(width 0.1)
				(type default)
			)
			(layer "F.Fab")
		)
		(fp_line
			(start -0.67945 -0.305054)
			(end -0.12065 -0.305054)
			(stroke
				(width 0.1)
				(type default)
			)
			(layer "F.Fab")
		)
		(fp_line
			(start -0.12065 -0.305054)
			(end -0.12065 -0.2794)
			(stroke
				(width 0.1)
				(type default)
			)
			(layer "F.Fab")
		)
		(pad "1" smd circle
			(at -0.40005 0 270)
			(size 0 0)
			(layers "F.Cu" "F.Mask" "F.Paste")
			(net "EN_P1V8")
		)
		(pad "2" smd circle
			(at 0.40005 0 270)
			(size 0 0)
			(layers "F.Cu" "F.Mask" "F.Paste")
			(net "EN_P1V8_R")
		)
	)
	(footprint ""
		(layer "F.Cu")
		(at 12.7762 -66.2432 180)
		(property "Reference" "PR242"
			(at 0 0 180)
			(layer "F.SilkS")
			(hide yes)
			(effects
				(font
					(size 1.27 1.27)
				)
			)
		)
		(property "Value" ""
			(at 0 0 180)
			(layer "F.Fab")
			(effects
				(font
					(size 1.27 1.27)
				)
			)
		)
		(duplicate_pad_numbers_are_jumpers no)
		(fp_line
			(start 0.7874 0.4064)
			(end -0.7874 0.4064)
			(stroke
				(width 0.1524)
				(type default)
			)
			(layer "F.SilkS")
		)
		(fp_line
			(start 0.7874 -0.4064)
			(end 0.7874 0.4064)
			(stroke
				(width 0.1524)
				(type default)
			)
			(layer "F.SilkS")
		)
		(fp_line
			(start -0.7874 0.4064)
			(end -0.7874 -0.4064)
			(stroke
				(width 0.1524)
				(type default)
			)
			(layer "F.SilkS")
		)
		(fp_line
			(start -0.7874 -0.4064)
			(end 0.7874 -0.4064)
			(stroke
				(width 0.1524)
				(type default)
			)
			(layer "F.SilkS")
		)
		(fp_line
			(start 0.67945 0.3048)
			(end 0.120396 0.3048)
			(stroke
				(width 0.1)
				(type default)
			)
			(layer "F.Fab")
		)
		(fp_line
			(start 0.67945 -0.3048)
			(end 0.67945 0.3048)
			(stroke
				(width 0.1)
				(type default)
			)
			(layer "F.Fab")
		)
		(fp_line
			(start 0.12065 -0.2794)
			(end 0.12065 -0.3048)
			(stroke
				(width 0.1)
				(type default)
			)
			(layer "F.Fab")
		)
		(fp_line
			(start 0.12065 -0.3048)
			(end 0.67945 -0.3048)
			(stroke
				(width 0.1)
				(type default)
			)
			(layer "F.Fab")
		)
		(fp_line
			(start 0.120396 0.3048)
			(end 0.120396 0.2794)
			(stroke
				(width 0.1)
				(type default)
			)
			(layer "F.Fab")
		)
		(fp_line
			(start 0.120396 0.2794)
			(end -0.12065 0.2794)
			(stroke
				(width 0.1)
				(type default)
			)
			(layer "F.Fab")
		)
		(fp_line
			(start -0.12065 0.3048)
			(end -0.67945 0.3048)
			(stroke
				(width 0.1)
				(type default)
			)
			(layer "F.Fab")
		)
		(fp_line
			(start -0.12065 0.2794)
			(end -0.12065 0.3048)
			(stroke
				(width 0.1)
				(type default)
			)
			(layer "F.Fab")
		)
		(fp_line
			(start -0.12065 -0.2794)
			(end 0.12065 -0.2794)
			(stroke
				(width 0.1)
				(type default)
			)
			(layer "F.Fab")
		)
		(fp_line
			(start -0.12065 -0.305054)
			(end -0.12065 -0.2794)
			(stroke
				(width 0.1)
				(type default)
			)
			(layer "F.Fab")
		)
		(fp_line
			(start -0.67945 0.3048)
			(end -0.67945 -0.305054)
			(stroke
				(width 0.1)
				(type default)
			)
			(layer "F.Fab")
		)
		(fp_line
			(start -0.67945 -0.305054)
			(end -0.12065 -0.305054)
			(stroke
				(width 0.1)
				(type default)
			)
			(layer "F.Fab")
		)
		(pad "1" smd circle
			(at -0.40005 0 180)
			(size 0 0)
			(layers "F.Cu" "F.Mask" "F.Paste")
			(net "P3V3_AUX")
		)
		(pad "2" smd circle
			(at 0.40005 0 180)
			(size 0 0)
			(layers "F.Cu" "F.Mask" "F.Paste")
			(net "PWRGD_P3V3_AUX_R")
		)
	)
)
